FILE_TYPE = MULTI_PHYS_TABLE;

PART 'IML3112Y2B000NCG8'

{========================================================================================}
:VALUE                | PART_TYPE | MATERIAL | PART_NUMBER    = STANDARD        | LIFECYCLE          | PART_NUMBER   | JEDEC_TYPE          | DESCRIPTION                     | MANUFTR | MANUF_PN             | RD_CMPLS_LVL | CMPLS_LVL | FROM_PJ   | CLASS | DIP_SMD | DATA                         | EE_CHECK_LIST | FP_ECN | PSL | CREATOR | STATUS | MSD | ESD_CDM | ESD_HBM | ESD_MM | PIN_LENGTH_SHORT_PIN | PIN_LENGTH_LONG_PIN | CREATEDAY  ;
{========================================================================================}
 'IML3112-Y2B000NCG8' | 'SMLF'    | 'IC'     | 'AL003112004'(!) = ''               | ''               | 'AL003112004' |'DFN8_TH_0-5_2X3XC'| 'IC(9P)IML3112-Y2B000NCG8(DFN)' | 'RTT'   | 'IML3112-Y2B000NCG8' | 'EP(V1)'     | ''        | 'T6G-JAY' | 'IC'  | ''      | 'RTT_IML3112-Y2B000NCG8.pdf' | ''            | ''     | ''  | ''      | ''     | ''  | ''      | ''      | ''     | '0 MILS'             | '0 MILS'            | '20210719'
 'IML3112-Y2B000NCG8' | 'SMLF'    | 'EMPTY'  | 'AL003112004'(!) = ''               | ''               | 'AL003112004' |'DFN8_TH_0-5_2X3XC'| 'IC(9P)IML3112-Y2B000NCG8(DFN)' | 'RTT'   | 'IML3112-Y2B000NCG8' | 'EP(V1)'     | ''        | 'T6G-JAY' | 'IC'  | ''      | 'RTT_IML3112-Y2B000NCG8.pdf' | ''            | ''     | ''  | ''      | ''     | ''  | ''      | ''      | ''     | '0 MILS'             | '0 MILS'            | '20210719'

END_PART

END.

